(kicad_pcb
	(version 20260206)
	(generator "pcbnew")
	(generator_version "10.0")
	(general
		(thickness 1.6)
		(legacy_teardrops no)
	)
	(paper "A4")
	(title_block
		(title "panther-plus-userver — 13130-1b_20150205.brd")
		(comment 1 "Honey Badger (Wiwynn) / footprints 1215-1217 of 1509")
	)
	(layers
		(0 "F.Cu" signal "TOP")
		(4 "In1.Cu" signal "L2")
		(6 "In2.Cu" signal "L3")
		(8 "In3.Cu" signal "L4")
		(10 "In4.Cu" signal "L5")
		(12 "In5.Cu" signal "L6")
		(14 "In6.Cu" signal "L7")
		(16 "In7.Cu" signal "L8")
		(18 "In8.Cu" signal "L9")
		(20 "In9.Cu" signal "L10")
		(22 "In10.Cu" signal "L11")
		(2 "B.Cu" signal "BOTTOM")
		(9 "F.Adhes" user "F.Adhesive")
		(11 "B.Adhes" user "B.Adhesive")
		(13 "F.Paste" user "Package Geometry/Pastemask Top")
		(15 "B.Paste" user "Package Geometry/Pastemask Bottom")
		(5 "F.SilkS" user "Ref Des/Silkscreen Top")
		(7 "B.SilkS" user "Ref Des/Silkscreen Bottom")
		(1 "F.Mask" user "Board Geometry/Soldermask Top")
		(3 "B.Mask" user "Board Geometry/Soldermask Bottom")
		(17 "Dwgs.User" user "User.Drawings")
		(19 "Cmts.User" user "User.Comments")
		(21 "Eco1.User" user "User.Eco1")
		(23 "Eco2.User" user "User.Eco2")
		(25 "Edge.Cuts" user "Board Geometry/Outline")
		(27 "Margin" user)
		(31 "F.CrtYd" user "Package Geometry/Place Bound Top")
		(29 "B.CrtYd" user "Package Geometry/Place Bound Bottom")
		(35 "F.Fab" user "Ref Des/Assembly Top")
		(33 "B.Fab" user "Ref Des/Assembly Bottom")
	)
	(footprint ""
		(layer "B.Cu")
		(at 106.426 -27.321002)
		(property "Reference" "C239"
			(at 0 0 0)
			(layer "B.SilkS")
			(hide yes)
			(effects
				(font
					(size 1.27 1.27)
				)
				(justify mirror)
			)
		)
		(property "Value" "SC1U10V2KX-1GP"
			(at -1.1811 -2.7051 0)
			(unlocked yes)
			(layer "B.Fab")
			(hide yes)
			(effects
				(font
					(size 1.016 1.016)
					(thickness 0.1524)
				)
				(justify mirror)
			)
		)
		(property "Device Type" "C402H22"
			(at -1.1811 -4.2291 0)
			(unlocked yes)
			(layer "B.Fab")
			(hide yes)
			(effects
				(font
					(size 1.016 1.016)
					(thickness 0.1524)
				)
				(justify mirror)
			)
		)
		(duplicate_pad_numbers_are_jumpers no)
		(fp_rect
			(start 0.381 0.7366)
			(end -0.381 -0.7366)
			(stroke
				(width 0)
				(type default)
			)
			(fill no)
			(layer "B.CrtYd")
		)
		(fp_rect
			(start 0.381 0.7366)
			(end -0.381 -0.7366)
			(stroke
				(width 0)
				(type default)
			)
			(fill no)
			(layer "B.Fab")
		)
		(pad "1" smd custom
			(at 0 -0.4572 180)
			(size 0.1143 0.1143)
			(layers "B.Cu" "B.Mask" "B.Paste")
			(net "PV_VDDR")
			(options
				(clearance outline)
				(anchor circle)
			)
			(primitives
				(gr_poly
					(pts
						(arc
							(start -0.254 0.1778)
							(mid -0.239121 0.213721)
							(end -0.2032 0.2286)
						)
						(arc
							(start 0.2032 0.2286)
							(mid 0.239121 0.213721)
							(end 0.254 0.1778)
						)
						(arc
							(start 0.254 -0.1778)
							(mid 0.239121 -0.213721)
							(end 0.2032 -0.2286)
						)
						(arc
							(start -0.2032 -0.2286)
							(mid -0.239121 -0.213721)
							(end -0.254 -0.1778)
						)
					)
					(width 0)
					(fill yes)
				)
			)
		)
		(pad "2" smd custom
			(at 0 0.4572 180)
			(size 0.1143 0.1143)
			(layers "B.Cu" "B.Mask" "B.Paste")
			(net "GND")
			(options
				(clearance outline)
				(anchor circle)
			)
			(primitives
				(gr_poly
					(pts
						(arc
							(start -0.254 0.1778)
							(mid -0.239121 0.213721)
							(end -0.2032 0.2286)
						)
						(arc
							(start 0.2032 0.2286)
							(mid 0.239121 0.213721)
							(end 0.254 0.1778)
						)
						(arc
							(start 0.254 -0.1778)
							(mid 0.239121 -0.213721)
							(end 0.2032 -0.2286)
						)
						(arc
							(start -0.2032 -0.2286)
							(mid -0.239121 -0.213721)
							(end -0.254 -0.1778)
						)
					)
					(width 0)
					(fill yes)
				)
			)
		)
	)
	(footprint ""
		(layer "B.Cu")
		(at 59.85002 -31.699962 -90)
		(property "Reference" "CN5"
			(at 0 0 90)
			(layer "B.SilkS")
			(hide yes)
			(effects
				(font
					(size 1.27 1.27)
				)
				(justify mirror)
			)
		)
		(property "Value" "SKT-MINI52P-67-GP-U"
			(at 17.5895 -7.0612 270)
			(unlocked yes)
			(layer "B.Fab")
			(hide yes)
			(effects
				(font
					(size 1.016 1.016)
					(thickness 0.1524)
				)
				(justify mirror)
			)
		)
		(property "Device Type" "80003-3021-U"
			(at 17.5895 -8.5852 270)
			(unlocked yes)
			(layer "B.Fab")
			(hide yes)
			(effects
				(font
					(size 1.016 1.016)
					(thickness 0.1524)
				)
				(justify mirror)
			)
		)
		(duplicate_pad_numbers_are_jumpers no)
		(fp_poly
			(pts
				(xy -12.4714 -5.8928) (xy -11.1506 -5.8928) (xy -11.811 -5.2324)
			)
			(stroke
				(width 0)
				(type default)
			)
			(fill yes)
			(layer "B.SilkS")
		)
		(fp_poly
			(pts
				(xy 12.079478 2.890012)
				(arc
					(start 12.079478 0.754126)
					(mid 11.636603 0)
					(end 12.079478 -0.754126)
				)
				(xy 12.079478 -2.890012) (xy -12.079478 -2.890012)
				(arc
					(start -12.079478 -1.021588)
					(mid -11.395309 0)
					(end -12.079478 1.021588)
				)
				(xy -12.079478 2.890012)
			)
			(stroke
				(width 0)
				(type default)
			)
			(fill yes)
			(layer "B.SilkS")
		)
		(fp_rect
			(start 15.9385 5.2324)
			(end -15.9385 -5.2324)
			(stroke
				(width 0)
				(type default)
			)
			(fill no)
			(layer "B.CrtYd")
		)
		(fp_rect
			(start 15.9385 5.2324)
			(end -15.9385 -5.2324)
			(stroke
				(width 0)
				(type default)
			)
			(fill no)
			(layer "B.Fab")
		)
		(pad "" np_thru_hole circle
			(at -12.500102 0 90)
			(size 0.254 0.254)
			(drill 1.6002)
			(layers "*.Cu" "*.Mask")
			(clearance 1.0287)
			(thermal_gap 1.0287)
		)
		(pad "" np_thru_hole circle
			(at 12.500102 0 90)
			(size 0.254 0.254)
			(drill 1.1176)
			(layers "*.Cu" "*.Mask")
			(clearance 0.7874)
			(thermal_gap 0.7874)
		)
		(pad "1" smd rect
			(at -11.800078 -4.096512 90)
			(size 0.5588 2.0066)
			(layers "B.Cu" "B.Mask" "B.Paste")
			(net "Net_448")
		)
		(pad "2" smd rect
			(at -11.400028 4.096512 90)
			(size 0.5588 2.0066)
			(layers "B.Cu" "B.Mask" "B.Paste")
			(net "P3V3")
		)
		(pad "3" smd rect
			(at -10.999978 -4.096512 90)
			(size 0.5588 2.0066)
			(layers "B.Cu" "B.Mask" "B.Paste")
			(net "Net_454")
		)
		(pad "4" smd rect
			(at -10.599928 4.096512 90)
			(size 0.5588 2.0066)
			(layers "B.Cu" "B.Mask" "B.Paste")
			(net "GND")
		)
		(pad "5" smd rect
			(at -10.199878 -4.096512 90)
			(size 0.5588 2.0066)
			(layers "B.Cu" "B.Mask" "B.Paste")
			(net "Net_453")
		)
		(pad "6" smd rect
			(at -9.800082 4.096512 90)
			(size 0.5588 2.0066)
			(layers "B.Cu" "B.Mask" "B.Paste")
			(net "Net_49")
		)
		(pad "7" smd rect
			(at -9.400032 -4.096512 90)
			(size 0.5588 2.0066)
			(layers "B.Cu" "B.Mask" "B.Paste")
			(net "Net_452")
		)
		(pad "8" smd rect
			(at -8.999982 4.096512 90)
			(size 0.5588 2.0066)
			(layers "B.Cu" "B.Mask" "B.Paste")
			(net "Net_459")
		)
		(pad "9" smd rect
			(at -8.599932 -4.096512 90)
			(size 0.5588 2.0066)
			(layers "B.Cu" "B.Mask" "B.Paste")
			(net "GND")
		)
		(pad "10" smd rect
			(at -8.199882 4.096512 90)
			(size 0.5588 2.0066)
			(layers "B.Cu" "B.Mask" "B.Paste")
			(net "Net_458")
		)
		(pad "11" smd rect
			(at -7.800086 -4.096512 90)
			(size 0.5588 2.0066)
			(layers "B.Cu" "B.Mask" "B.Paste")
			(net "Net_451")
		)
		(pad "12" smd rect
			(at -7.400036 4.096512 90)
			(size 0.5588 2.0066)
			(layers "B.Cu" "B.Mask" "B.Paste")
			(net "Net_457")
		)
		(pad "13" smd rect
			(at -6.999986 -4.096512 90)
			(size 0.5588 2.0066)
			(layers "B.Cu" "B.Mask" "B.Paste")
			(net "Net_450")
		)
		(pad "14" smd rect
			(at -6.599936 4.096512 90)
			(size 0.5588 2.0066)
			(layers "B.Cu" "B.Mask" "B.Paste")
			(net "Net_456")
		)
		(pad "15" smd rect
			(at -6.199886 -4.096512 90)
			(size 0.5588 2.0066)
			(layers "B.Cu" "B.Mask" "B.Paste")
			(net "GND")
		)
		(pad "16" smd rect
			(at -5.80009 4.096512 90)
			(size 0.5588 2.0066)
			(layers "B.Cu" "B.Mask" "B.Paste")
			(net "Net_455")
		)
		(pad "17" smd rect
			(at -2.199894 -4.096512 90)
			(size 0.5588 2.0066)
			(layers "B.Cu" "B.Mask" "B.Paste")
			(net "Net_461")
		)
		(pad "18" smd rect
			(at -1.800098 4.096512 90)
			(size 0.5588 2.0066)
			(layers "B.Cu" "B.Mask" "B.Paste")
			(net "GND")
		)
		(pad "19" smd rect
			(at -1.400048 -4.096512 90)
			(size 0.5588 2.0066)
			(layers "B.Cu" "B.Mask" "B.Paste")
			(net "Net_460")
		)
		(pad "20" smd rect
			(at -0.999998 4.096512 90)
			(size 0.5588 2.0066)
			(layers "B.Cu" "B.Mask" "B.Paste")
			(net "Net_464")
		)
		(pad "21" smd rect
			(at -0.599948 -4.096512 90)
			(size 0.5588 2.0066)
			(layers "B.Cu" "B.Mask" "B.Paste")
			(net "GND")
		)
		(pad "22" smd rect
			(at -0.199898 4.096512 90)
			(size 0.5588 2.0066)
			(layers "B.Cu" "B.Mask" "B.Paste")
			(net "Net_463")
		)
		(pad "23" smd rect
			(at 0.199898 -4.096512 90)
			(size 0.5588 2.0066)
			(layers "B.Cu" "B.Mask" "B.Paste")
			(net "SATA3_RX_C_DP0")
		)
		(pad "24" smd rect
			(at 0.599948 4.096512 90)
			(size 0.5588 2.0066)
			(layers "B.Cu" "B.Mask" "B.Paste")
			(net "P3V3")
		)
		(pad "25" smd rect
			(at 0.999998 -4.096512 90)
			(size 0.5588 2.0066)
			(layers "B.Cu" "B.Mask" "B.Paste")
			(net "SATA3_RX_C_DN0")
		)
		(pad "26" smd rect
			(at 1.400048 4.096512 90)
			(size 0.5588 2.0066)
			(layers "B.Cu" "B.Mask" "B.Paste")
			(net "GND")
		)
		(pad "27" smd rect
			(at 1.800098 -4.096512 90)
			(size 0.5588 2.0066)
			(layers "B.Cu" "B.Mask" "B.Paste")
			(net "GND")
		)
		(pad "28" smd rect
			(at 2.199894 4.096512 90)
			(size 0.5588 2.0066)
			(layers "B.Cu" "B.Mask" "B.Paste")
			(net "Net_47")
		)
		(pad "29" smd rect
			(at 2.599944 -4.096512 90)
			(size 0.5588 2.0066)
			(layers "B.Cu" "B.Mask" "B.Paste")
			(net "GND")
		)
		(pad "30" smd rect
			(at 2.999994 4.096512 90)
			(size 0.5588 2.0066)
			(layers "B.Cu" "B.Mask" "B.Paste")
			(net "Net_462")
		)
		(pad "31" smd rect
			(at 3.400044 -4.096512 90)
			(size 0.5588 2.0066)
			(layers "B.Cu" "B.Mask" "B.Paste")
			(net "SATA3_TX_C_DN0")
		)
		(pad "32" smd rect
			(at 3.800094 4.096512 90)
			(size 0.5588 2.0066)
			(layers "B.Cu" "B.Mask" "B.Paste")
			(net "Net_476")
		)
		(pad "33" smd rect
			(at 4.19989 -4.096512 90)
			(size 0.5588 2.0066)
			(layers "B.Cu" "B.Mask" "B.Paste")
			(net "SATA3_TX_C_DP0")
		)
		(pad "34" smd rect
			(at 4.59994 4.096512 90)
			(size 0.5588 2.0066)
			(layers "B.Cu" "B.Mask" "B.Paste")
			(net "GND")
		)
		(pad "35" smd rect
			(at 4.99999 -4.096512 90)
			(size 0.5588 2.0066)
			(layers "B.Cu" "B.Mask" "B.Paste")
			(net "GND")
		)
		(pad "36" smd rect
			(at 5.40004 4.096512 90)
			(size 0.5588 2.0066)
			(layers "B.Cu" "B.Mask" "B.Paste")
			(net "Net_475")
		)
		(pad "37" smd rect
			(at 5.80009 -4.096512 90)
			(size 0.5588 2.0066)
			(layers "B.Cu" "B.Mask" "B.Paste")
			(net "Net_470")
		)
		(pad "38" smd rect
			(at 6.199886 4.096512 90)
			(size 0.5588 2.0066)
			(layers "B.Cu" "B.Mask" "B.Paste")
			(net "Net_474")
		)
		(pad "39" smd rect
			(at 6.599936 -4.096512 90)
			(size 0.5588 2.0066)
			(layers "B.Cu" "B.Mask" "B.Paste")
			(net "Net_469")
		)
		(pad "40" smd rect
			(at 6.999986 4.096512 90)
			(size 0.5588 2.0066)
			(layers "B.Cu" "B.Mask" "B.Paste")
			(net "GND")
		)
		(pad "41" smd rect
			(at 7.400036 -4.096512 90)
			(size 0.5588 2.0066)
			(layers "B.Cu" "B.Mask" "B.Paste")
			(net "Net_468")
		)
		(pad "42" smd rect
			(at 7.800086 4.096512 90)
			(size 0.5588 2.0066)
			(layers "B.Cu" "B.Mask" "B.Paste")
			(net "Net_473")
		)
		(pad "43" smd rect
			(at 8.199882 -4.096512 90)
			(size 0.5588 2.0066)
			(layers "B.Cu" "B.Mask" "B.Paste")
			(net "Net_467")
		)
		(pad "44" smd rect
			(at 8.599932 4.096512 90)
			(size 0.5588 2.0066)
			(layers "B.Cu" "B.Mask" "B.Paste")
			(net "Net_472")
		)
		(pad "45" smd rect
			(at 8.999982 -4.096512 90)
			(size 0.5588 2.0066)
			(layers "B.Cu" "B.Mask" "B.Paste")
			(net "Net_466")
		)
		(pad "46" smd rect
			(at 9.400032 4.096512 90)
			(size 0.5588 2.0066)
			(layers "B.Cu" "B.Mask" "B.Paste")
			(net "Net_471")
		)
		(pad "47" smd rect
			(at 9.800082 -4.096512 90)
			(size 0.5588 2.0066)
			(layers "B.Cu" "B.Mask" "B.Paste")
			(net "Net_465")
		)
		(pad "48" smd rect
			(at 10.199878 4.096512 90)
			(size 0.5588 2.0066)
			(layers "B.Cu" "B.Mask" "B.Paste")
			(net "Net_48")
		)
		(pad "49" smd rect
			(at 10.599928 -4.096512 90)
			(size 0.5588 2.0066)
			(layers "B.Cu" "B.Mask" "B.Paste")
			(net "MSATA_ACT#")
		)
		(pad "50" smd rect
			(at 10.999978 4.096512 90)
			(size 0.5588 2.0066)
			(layers "B.Cu" "B.Mask" "B.Paste")
			(net "GND")
		)
		(pad "51" smd rect
			(at 11.400028 -4.096512 90)
			(size 0.5588 2.0066)
			(layers "B.Cu" "B.Mask" "B.Paste")
			(net "MSATA_PRESENT_R#")
		)
		(pad "52" smd rect
			(at 11.800078 4.096512 90)
			(size 0.5588 2.0066)
			(layers "B.Cu" "B.Mask" "B.Paste")
			(net "P3V3")
		)
		(pad "53" smd rect
			(at -14.649958 -3.50012 90)
			(size 2.3114 3.2004)
			(layers "B.Cu" "B.Mask" "B.Paste")
			(net "GND")
		)
		(pad "54" smd rect
			(at 14.649958 -3.50012 90)
			(size 2.3114 3.2004)
			(layers "B.Cu" "B.Mask" "B.Paste")
			(net "GND")
		)
		(zone
			(layers "F.Cu" "B.Cu" "In1.Cu" "In2.Cu" "In3.Cu" "In4.Cu" "In5.Cu" "In6.Cu"
				"In7.Cu" "In8.Cu" "In9.Cu" "In10.Cu"
			)
			(hatch none 0.5)
			(connect_pads
				(clearance 0)
			)
			(min_thickness 0.25)
			(keepout
				(tracks not_allowed)
				(vias allowed)
				(pads allowed)
				(copperpour not_allowed)
				(footprints allowed)
			)
			(placement
				(enabled no)
				(sheetname "")
			)
			(fill
				(thermal_gap 0.5)
				(thermal_bridge_width 0.5)
				(island_removal_mode 0)
			)
			(polygon
				(pts
					(arc
						(start 60.71362 -19.19986)
						(mid 58.98642 -19.19986)
						(end 60.71362 -19.19986)
					)
				)
			)
		)
		(zone
			(layers "F.Cu" "B.Cu" "In1.Cu" "In2.Cu" "In3.Cu" "In4.Cu" "In5.Cu" "In6.Cu"
				"In7.Cu" "In8.Cu" "In9.Cu" "In10.Cu"
			)
			(hatch none 0.5)
			(connect_pads
				(clearance 0)
			)
			(min_thickness 0.25)
			(keepout
				(tracks not_allowed)
				(vias allowed)
				(pads allowed)
				(copperpour not_allowed)
				(footprints allowed)
			)
			(placement
				(enabled no)
				(sheetname "")
			)
			(fill
				(thermal_gap 0.5)
				(thermal_bridge_width 0.5)
				(island_removal_mode 0)
			)
			(polygon
				(pts
					(arc
						(start 60.95492 -44.200064)
						(mid 58.74512 -44.200064)
						(end 60.95492 -44.200064)
					)
				)
			)
		)
		(zone
			(layer "B.Cu")
			(hatch none 0.5)
			(connect_pads
				(clearance 0)
			)
			(min_thickness 0.25)
			(keepout
				(tracks allowed)
				(vias not_allowed)
				(pads allowed)
				(copperpour not_allowed)
				(footprints allowed)
			)
			(placement
				(enabled no)
				(sheetname "")
			)
			(fill
				(thermal_gap 0.5)
				(thermal_bridge_width 0.5)
				(island_removal_mode 0)
			)
			(polygon
				(pts
					(xy 56.756808 -37.220652) (xy 56.756808 -43.37939) (xy 57.264808 -43.37939) (xy 57.264808 -37.220652)
				)
			)
		)
		(zone
			(layer "B.Cu")
			(hatch none 0.5)
			(connect_pads
				(clearance 0)
			)
			(min_thickness 0.25)
			(keepout
				(tracks allowed)
				(vias not_allowed)
				(pads allowed)
				(copperpour not_allowed)
				(footprints allowed)
			)
			(placement
				(enabled no)
				(sheetname "")
			)
			(fill
				(thermal_gap 0.5)
				(thermal_bridge_width 0.5)
				(island_removal_mode 0)
			)
			(polygon
				(pts
					(xy 56.756808 -19.620484) (xy 56.756808 -33.77946) (xy 57.264808 -33.77946) (xy 57.264808 -19.620484)
				)
			)
		)
		(zone
			(layer "B.Cu")
			(hatch none 0.5)
			(connect_pads
				(clearance 0)
			)
			(min_thickness 0.25)
			(keepout
				(tracks allowed)
				(vias not_allowed)
				(pads allowed)
				(copperpour not_allowed)
				(footprints allowed)
			)
			(placement
				(enabled no)
				(sheetname "")
			)
			(fill
				(thermal_gap 0.5)
				(thermal_bridge_width 0.5)
				(island_removal_mode 0)
			)
			(polygon
				(pts
					(xy 62.435232 -37.620448) (xy 62.435232 -43.77944) (xy 62.943232 -43.77944) (xy 62.943232 -37.620448)
				)
			)
		)
		(zone
			(layer "B.Cu")
			(hatch none 0.5)
			(connect_pads
				(clearance 0)
			)
			(min_thickness 0.25)
			(keepout
				(tracks allowed)
				(vias not_allowed)
				(pads allowed)
				(copperpour not_allowed)
				(footprints allowed)
			)
			(placement
				(enabled no)
				(sheetname "")
			)
			(fill
				(thermal_gap 0.5)
				(thermal_bridge_width 0.5)
				(island_removal_mode 0)
			)
			(polygon
				(pts
					(xy 62.435232 -20.020534) (xy 62.435232 -34.179256) (xy 62.943232 -34.179256) (xy 62.943232 -20.020534)
				)
			)
		)
	)
	(footprint ""
		(layer "B.Cu")
		(at 38.989 -50.3682 90)
		(property "Reference" "R129"
			(at 0 0 90)
			(layer "B.SilkS")
			(hide yes)
			(effects
				(font
					(size 1.27 1.27)
				)
				(justify mirror)
			)
		)
		(property "Value" "0R2J-2-GP"
			(at -1.7907 -1.1176 90)
			(unlocked yes)
			(layer "B.Fab")
			(hide yes)
			(effects
				(font
					(size 1.016 1.016)
					(thickness 0.1524)
				)
				(justify mirror)
			)
		)
		(property "Device Type" "R402H16"
			(at -1.7907 -2.6416 90)
			(unlocked yes)
			(layer "B.Fab")
			(hide yes)
			(effects
				(font
					(size 1.016 1.016)
					(thickness 0.1524)
				)
				(justify mirror)
			)
		)
		(duplicate_pad_numbers_are_jumpers no)
		(fp_rect
			(start 0.381 0.8382)
			(end -0.381 -0.8382)
			(stroke
				(width 0)
				(type default)
			)
			(fill no)
			(layer "B.CrtYd")
		)
		(fp_rect
			(start 0.381 0.8382)
			(end -0.381 -0.8382)
			(stroke
				(width 0)
				(type default)
			)
			(fill no)
			(layer "B.Fab")
		)
		(pad "1" smd custom
			(at 0 -0.4318 270)
			(size 0.127 0.127)
			(layers "B.Cu" "B.Mask" "B.Paste")
			(net "SMB_HOST_LV_CLK")
			(options
				(clearance outline)
				(anchor circle)
			)
			(primitives
				(gr_poly
					(pts
						(arc
							(start -0.2032 0.2794)
							(mid -0.239121 0.264521)
							(end -0.254 0.2286)
						)
						(arc
							(start -0.254 -0.2286)
							(mid -0.239121 -0.264521)
							(end -0.2032 -0.2794)
						)
						(arc
							(start 0.2032 -0.2794)
							(mid 0.239121 -0.264521)
							(end 0.254 -0.2286)
						)
						(arc
							(start 0.254 0.2286)
							(mid 0.239121 0.264521)
							(end 0.2032 0.2794)
						)
					)
					(width 0)
					(fill yes)
				)
			)
		)
		(pad "2" smd custom
			(at 0 0.4318 270)
			(size 0.127 0.127)
			(layers "B.Cu" "B.Mask" "B.Paste")
			(net "SMB_CLKGEN_R_CLK")
			(options
				(clearance outline)
				(anchor circle)
			)
			(primitives
				(gr_poly
					(pts
						(arc
							(start -0.2032 0.2794)
							(mid -0.239121 0.264521)
							(end -0.254 0.2286)
						)
						(arc
							(start -0.254 -0.2286)
							(mid -0.239121 -0.264521)
							(end -0.2032 -0.2794)
						)
						(arc
							(start 0.2032 -0.2794)
							(mid 0.239121 -0.264521)
							(end 0.254 -0.2286)
						)
						(arc
							(start 0.254 0.2286)
							(mid 0.239121 0.264521)
							(end 0.2032 0.2794)
						)
					)
					(width 0)
					(fill yes)
				)
			)
		)
	)
)
